Altium Designer Pick and Place Locations
C:\<user>\research\users\<user>\Tasks\T131322016 - SA45 Daughter Card\outputs\assembly_SA45_DaughterCard\xydata\SA45_DaughterCard-RevX1_xydata.txt

========================================================================================================================
File Design Information:

Date:       24/01/23
Time:       17:30
Revision:   Not in VersionControl
Variant:    SA45
Units used: mm

Designator Comment                          Layer       Footprint                           Center-X(mm) Center-Y(mm) Rotation Description                                        
J6         Keystone_4871                    BottomLayer Keystone_4871                       4.4000       38.6000      180      ""                                                 
J5         Keystone_4871                    BottomLayer Keystone_4871                       36.2000      40.1000      180      ""                                                 
J4         Keystone_4871                    BottomLayer Keystone_4871                       35.5000      -1.0000      180      ""                                                 
J3         Keystone_4871                    BottomLayer Keystone_4871                       4.4000       2.0000       180      ""                                                 
P10        Mill-Max_8600-0-05-80-00-00-03-0 BottomLayer TH001V_109DIA_000mt_8600-0          14.2700      43.3300      180      "CONN, PC PIN, PRESS-FIT, 10.16MM LENGTH, TIN, TH" 
P9         Mill-Max_8600-0-05-80-00-00-03-0 BottomLayer TH001V_109DIA_000mt_8600-0          11.2220      43.3300      180      "CONN, PC PIN, PRESS-FIT, 10.16MM LENGTH, TIN, TH" 
P8         Mill-Max_8600-0-05-80-00-00-03-0 BottomLayer TH001V_109DIA_000mt_8600-0          8.1740       43.3300      180      "CONN, PC PIN, PRESS-FIT, 10.16MM LENGTH, TIN, TH" 
P7         Mill-Max_8600-0-05-80-00-00-03-0 BottomLayer TH001V_109DIA_000mt_8600-0          5.1260       43.3300      180      "CONN, PC PIN, PRESS-FIT, 10.16MM LENGTH, TIN, TH" 
P6         Mill-Max_8600-0-05-80-00-00-03-0 BottomLayer TH001V_109DIA_000mt_8600-0          2.0780       43.3300      180      "CONN, PC PIN, PRESS-FIT, 10.16MM LENGTH, TIN, TH" 
P5         Mill-Max_8600-0-05-80-00-00-03-0 BottomLayer TH001V_109DIA_000mt_8600-0          0.0000       0.0000       180      "CONN, PC PIN, PRESS-FIT, 10.16MM LENGTH, TIN, TH" 
P4         Mill-Max_8600-0-05-80-00-00-03-0 BottomLayer TH001V_109DIA_000mt_8600-0          0.0000       40.6400      180      "CONN, PC PIN, PRESS-FIT, 10.16MM LENGTH, TIN, TH" 
P3         Mill-Max_8600-0-05-80-00-00-03-0 BottomLayer TH001V_109DIA_000mt_8600-0          40.6400      40.6400      180      "CONN, PC PIN, PRESS-FIT, 10.16MM LENGTH, TIN, TH" 
P2         Mill-Max_8600-0-05-80-00-00-03-0 BottomLayer TH001V_109DIA_000mt_8600-0          40.6800      20.3400      180      "CONN, PC PIN, PRESS-FIT, 10.16MM LENGTH, TIN, TH" 
P1         Mill-Max_8600-0-05-80-00-00-03-0 BottomLayer TH001V_109DIA_000mt_8600-0          40.6400      0.0000       180      "CONN, PC PIN, PRESS-FIT, 10.16MM LENGTH, TIN, TH" 
R2         Yageo_RC0402FR-0791KL            BottomLayer RESC1005X040N                       14.3850      19.1650      0        "RES SMD 91K OHM 1% 1/16W 0402"                    
R6         Yageo_RC0201JR-070RL             BottomLayer RESC0603X026N                       15.8650      20.5550      90       "RES, 0.0 OHM, 0.5A, 1/20W, 0201"                  
L1         4.7uH                            BottomLayer Eaton_HCM0703-4R7-R                 23.4150      16.8525      0        ""                                                 
R4         Yageo_RC0402FR-0730KL            BottomLayer RESC1005X040N                       14.3850      18.0150      180      "RES SMD 30K OHM 1% 1/16W 0402"                    
C12        Murata_GRM155R61H104KE14D        BottomLayer CAPC1005X055N                       23.4150      12.2900      180      "CAP, CER, X5R, 0.10UF, 10%, 50V, 0402, 0.55MM T"  
U3         DiodesInc_AP63356QZV-7           BottomLayer DiodesInc_AP63356QZV-7              17.1650      17.8963      0        ""                                                 
R3         Yageo_RC1206JR-070RL             BottomLayer RESC3216X070N                       33.7400      7.6400       0        "RES, 0 OHM, 2A, 1/4W, 1206"                       
C3         Murata_GRM155R61H104KE14D        BottomLayer CAPC1005X055N                       18.6800      21.1750      0        "CAP, CER, X5R, 0.10UF, 10%, 50V, 0402, 0.55MM T"  
C5         Murata_GRM21BR6YA106KE43L        BottomLayer CAPC2013X145N                       16.8150      9.7900       0        "CAP, CER, X5R, 10UF, 10%, 35V, 0805, 1.45MM T"    
C2         Murata_GRM155R61H104KE14D        BottomLayer CAPC1005X055N                       40.0900      8.1000       90       "CAP, CER, X5R, 0.10UF, 10%, 50V, 0402, 0.55MM T"  
C1         Murata_GRM155R6YA105KE11D        BottomLayer CAPC1005X061N                       38.3100      9.9400       0        "CAP, CER, X5R, 1UF, 10%, 35V, 0402, 0.55MM T"     
C4         Murata_GRM0335C1E330JA01D        BottomLayer CAPC0603X033N                       14.8650      20.5450      270      "CAP, CER, NP0, 33PF, 5%, 25V, 0201, 0.33MM T"     
J2         Wurth_9774040243R                BottomLayer TH000V_300DIAx400_001mt_9774040243R 20.2400      42.1400      180      "STANDOFF, ROUND, M2X0.4 STEEL 4MM, 9774040243R"   
J1         Wurth_9774040243R                BottomLayer TH000V_300DIAx400_001mt_9774040243R 20.4400      -1.2600      180      "STANDOFF, ROUND, M2X0.4 STEEL 4MM, 9774040243R"   
C11        Murata_GRM21BR61A226ME51L        BottomLayer CAPC2013X140N                       23.3150      7.7900       180      "CAP, CER, X5R, 22UF, 20%, 10V, 0805, 1.40MM T"    
C10        Murata_GRM21BR61A226ME51L        BottomLayer CAPC2013X140N                       23.3150      10.2900      180      "CAP, CER, X5R, 22UF, 20%, 10V, 0805, 1.40MM T"    
C6         Murata_GRM155R61H104KE14D        BottomLayer CAPC1005X055N                       17.1150      14.7900      0        "CAP, CER, X5R, 0.10UF, 10%, 50V, 0402, 0.55MM T"  
C8         Murata_GRM21BR61A226ME51L        BottomLayer CAPC2013X140N                       16.8150      7.3900       0        "CAP, CER, X5R, 22UF, 20%, 10V, 0805, 1.40MM T"    
C7         Murata_GRM21BR6YA106KE43L        BottomLayer CAPC2013X145N                       16.8150      12.3900      0        "CAP, CER, X5R, 10UF, 10%, 35V, 0805, 1.45MM T"    
U1         Microchip_SA45                   TopLayer    Microchip_SA45                      21.3400      20.3400      180      ""                                                 
